(kicad_pcb
	(version 20221018)
	(generator pcbnew)
	(general
    (thickness 1.586)
  )
	(paper "A4")
	(title_block
    (date "2024-03-26")
    (rev "1.1.3")
		(comment 9 "footprints 25-33 of 146")
	)
	(layers
    (0 "F.Cu" signal)
    (1 "In1.Cu" power)
    (2 "In2.Cu" power)
    (31 "B.Cu" signal)
    (32 "B.Adhes" user "B.Adhesive")
    (33 "F.Adhes" user "F.Adhesive")
    (34 "B.Paste" user)
    (35 "F.Paste" user)
    (36 "B.SilkS" user "B.Silkscreen")
    (37 "F.SilkS" user "F.Silkscreen")
    (38 "B.Mask" user)
    (39 "F.Mask" user)
    (40 "Dwgs.User" user "User.Drawings")
    (41 "Cmts.User" user "User.Comments")
    (42 "Eco1.User" user "User.Eco1")
    (43 "Eco2.User" user "User.Eco2")
    (44 "Edge.Cuts" user)
    (45 "Margin" user)
    (46 "B.CrtYd" user "B.Courtyard")
    (47 "F.CrtYd" user "F.Courtyard")
    (48 "B.Fab" user)
    (49 "F.Fab" user)
  )
	(footprint "scalenode-cm4-baseboard-footprints:R_0402_1005Metric" (layer "F.Cu")
    (at 166.26456 74.33512)
    (descr "Resistor SMD 0402")
    (tags "resistor SMD 0402")
    (property "Author" "Antmicro")
    (property "License" "Apache-2.0")
    (property "MPN" "CR0402-FX-22R0GLF")
    (property "Manufacturer" "Bourns")
    (property "Sheetfile" "interfaces.kicad_sch")
    (property "Sheetname" "Interfaces")
    (property "Tolerance" "1%")
    (property "Val" "22R")
    (property "ki_description" "22R resistor in 0402 package with 1% tolerance")
    (attr smd)
    (fp_text reference "R58" (at -1.11456 1.43988) (layer "F.SilkS")
        (effects (font (size 0.7 0.7) (thickness 0.15)) (justify left bottom))
    )
    (fp_text value "R_22R_0402" (at 0 1.4) (layer "F.Fab")
        (effects (font (size 0.7 0.7) (thickness 0.15)) (justify left bottom))
    )
    (fp_text user "License: Apache-2.0" (at -0.95 5.169) (layer "F.Fab") hide
        (effects (font (size 0.7 0.7) (thickness 0.15)) (justify left bottom))
    )
    (fp_text user "Author: Antmicro" (at -0.95 4.169) (layer "F.Fab") hide
        (effects (font (size 0.7 0.7) (thickness 0.15)) (justify left bottom))
    )
    (fp_text user "${REFERENCE}" (at -0.95 3.168) (layer "F.Fab") hide
        (effects (font (size 0.7 0.7) (thickness 0.15)) (justify left bottom))
    )
    (fp_rect (start -0.95 -0.48) (end 0.95 0.48)
      (stroke (width 0.05) (type solid)) (fill none) (layer "F.CrtYd"))
    (fp_rect (start -0.5 -0.25) (end 0.5 0.25)
      (stroke (width 0.15) (type solid)) (fill none) (layer "F.Fab"))
    (pad "1" smd roundrect (at -0.485 0) (size 0.59 0.64) (layers "F.Cu" "F.Paste" "F.Mask") (roundrect_rratio 0.25)
      (net 249 "/Interfaces/FTDI_USB_N") (pintype "passive"))
    (pad "2" smd roundrect (at 0.485 0) (size 0.59 0.64) (layers "F.Cu" "F.Paste" "F.Mask") (roundrect_rratio 0.25)
      (net 266 "Net-(U6-USBDM)") (pintype "passive"))
  )
	(footprint "scalenode-cm4-baseboard-footprints:R_0402_1005Metric" (layer "F.Cu")
    (at 158.89224 71.05344 180)
    (descr "Resistor SMD 0402")
    (tags "resistor SMD 0402")
    (property "Author" "Antmicro")
    (property "License" "Apache-2.0")
    (property "MPN" "CR0402-FX-2200GLF")
    (property "Manufacturer" "Bourns")
    (property "Sheetfile" "interfaces.kicad_sch")
    (property "Sheetname" "Interfaces")
    (property "Tolerance" "1%")
    (property "Val" "220R")
    (property "ki_description" "220R resistor in 0402 package with 1% tolerance")
    (attr smd)
    (fp_text reference "R60" (at 1.09224 0.62844 180) (layer "F.SilkS")
        (effects (font (size 0.7 0.7) (thickness 0.15)) (justify left bottom))
    )
    (fp_text value "R_220R_0402" (at 0 1.4 180) (layer "F.Fab")
        (effects (font (size 0.7 0.7) (thickness 0.15)) (justify left bottom))
    )
    (fp_text user "License: Apache-2.0" (at -0.95 5.169 180) (layer "F.Fab") hide
        (effects (font (size 0.7 0.7) (thickness 0.15)) (justify left bottom))
    )
    (fp_text user "${REFERENCE}" (at -0.95 3.168 180) (layer "F.Fab") hide
        (effects (font (size 0.7 0.7) (thickness 0.15)) (justify left bottom))
    )
    (fp_text user "Author: Antmicro" (at -0.95 4.169 180) (layer "F.Fab") hide
        (effects (font (size 0.7 0.7) (thickness 0.15)) (justify left bottom))
    )
    (fp_rect (start -0.95 -0.48) (end 0.95 0.48)
      (stroke (width 0.05) (type solid)) (fill none) (layer "F.CrtYd"))
    (fp_rect (start -0.5 -0.25) (end 0.5 0.25)
      (stroke (width 0.15) (type solid)) (fill none) (layer "F.Fab"))
    (pad "1" smd roundrect (at -0.485 0 180) (size 0.59 0.64) (layers "F.Cu" "F.Paste" "F.Mask") (roundrect_rratio 0.25)
      (net 268 "Net-(U6-TXD)") (pintype "passive"))
    (pad "2" smd roundrect (at 0.485 0 180) (size 0.59 0.64) (layers "F.Cu" "F.Paste" "F.Mask") (roundrect_rratio 0.25)
      (net 241 "RPi_RXD") (pintype "passive"))
  )
	(footprint "scalenode-cm4-baseboard-footprints:R_0402_1005Metric" (layer "F.Cu")
    (at 158.37916 71.5602 90)
    (descr "Resistor SMD 0402")
    (tags "resistor SMD 0402")
    (property "Author" "Antmicro")
    (property "DNP" "DNP")
    (property "License" "Apache-2.0")
    (property "MPN" "CR0402-FX-2200GLF")
    (property "Manufacturer" "Bourns")
    (property "Sheetfile" "interfaces.kicad_sch")
    (property "Sheetname" "Interfaces")
    (property "Tolerance" "1%")
    (property "Val" "220R")
    (property "dnp" "")
    (property "exclude_from_bom" "")
    (property "ki_description" "220R resistor in 0402 package with 1% tolerance")
    (attr exclude_from_pos_files exclude_from_bom)
    (fp_text reference "R61" (at -1.0648 -0.62916 90) (layer "F.SilkS")
        (effects (font (size 0.7 0.7) (thickness 0.15)) (justify left bottom))
    )
    (fp_text value "R_220R_0402" (at 0 1.4 90) (layer "F.Fab")
        (effects (font (size 0.7 0.7) (thickness 0.15)) (justify left bottom))
    )
    (fp_text user "License: Apache-2.0" (at -0.95 5.169 90) (layer "F.Fab") hide
        (effects (font (size 0.7 0.7) (thickness 0.15)) (justify left bottom))
    )
    (fp_text user "${REFERENCE}" (at -0.95 3.168 90) (layer "F.Fab") hide
        (effects (font (size 0.7 0.7) (thickness 0.15)) (justify left bottom))
    )
    (fp_text user "Author: Antmicro" (at -0.95 4.169 90) (layer "F.Fab") hide
        (effects (font (size 0.7 0.7) (thickness 0.15)) (justify left bottom))
    )
    (fp_rect (start -0.95 -0.48) (end 0.95 0.48)
      (stroke (width 0.05) (type solid)) (fill none) (layer "F.CrtYd"))
    (fp_rect (start -0.5 -0.25) (end 0.5 0.25)
      (stroke (width 0.15) (type solid)) (fill none) (layer "F.Fab"))
    (pad "1" smd roundrect (at -0.485 0 90) (size 0.59 0.64) (layers "F.Cu" "F.Paste" "F.Mask") (roundrect_rratio 0.25)
      (net 238 "Adapter_TXD") (pintype "passive"))
    (pad "2" smd roundrect (at 0.485 0 90) (size 0.59 0.64) (layers "F.Cu" "F.Paste" "F.Mask") (roundrect_rratio 0.25)
      (net 241 "RPi_RXD") (pintype "passive"))
  )
	(footprint "scalenode-cm4-baseboard-footprints:R_0402_1005Metric" (layer "F.Cu")
    (at 155.70104 71.0708)
    (descr "Resistor SMD 0402")
    (tags "resistor SMD 0402")
    (property "Author" "Antmicro")
    (property "License" "Apache-2.0")
    (property "MPN" "CR0402-FX-2200GLF")
    (property "Manufacturer" "Bourns")
    (property "Sheetfile" "interfaces.kicad_sch")
    (property "Sheetname" "Interfaces")
    (property "Tolerance" "1%")
    (property "Val" "220R")
    (property "ki_description" "220R resistor in 0402 package with 1% tolerance")
    (attr smd)
    (fp_text reference "R56" (at -1.10104 -0.6208) (layer "F.SilkS")
        (effects (font (size 0.7 0.7) (thickness 0.15)) (justify left bottom))
    )
    (fp_text value "R_220R_0402" (at 0 1.4) (layer "F.Fab")
        (effects (font (size 0.7 0.7) (thickness 0.15)) (justify left bottom))
    )
    (fp_text user "License: Apache-2.0" (at -0.95 5.169) (layer "F.Fab") hide
        (effects (font (size 0.7 0.7) (thickness 0.15)) (justify left bottom))
    )
    (fp_text user "${REFERENCE}" (at -0.95 3.168) (layer "F.Fab") hide
        (effects (font (size 0.7 0.7) (thickness 0.15)) (justify left bottom))
    )
    (fp_text user "Author: Antmicro" (at -0.95 4.169) (layer "F.Fab") hide
        (effects (font (size 0.7 0.7) (thickness 0.15)) (justify left bottom))
    )
    (fp_rect (start -0.95 -0.48) (end 0.95 0.48)
      (stroke (width 0.05) (type solid)) (fill none) (layer "F.CrtYd"))
    (fp_rect (start -0.5 -0.25) (end 0.5 0.25)
      (stroke (width 0.15) (type solid)) (fill none) (layer "F.Fab"))
    (pad "1" smd roundrect (at -0.485 0) (size 0.59 0.64) (layers "F.Cu" "F.Paste" "F.Mask") (roundrect_rratio 0.25)
      (net 242 "RPi_TXD") (pintype "passive"))
    (pad "2" smd roundrect (at 0.485 0) (size 0.59 0.64) (layers "F.Cu" "F.Paste" "F.Mask") (roundrect_rratio 0.25)
      (net 265 "Net-(U6-RXD)") (pintype "passive"))
  )
	(footprint "scalenode-cm4-baseboard-footprints:R_0402_1005Metric" (layer "F.Cu")
    (at 155.18288 71.5801 -90)
    (descr "Resistor SMD 0402")
    (tags "resistor SMD 0402")
    (property "Author" "Antmicro")
    (property "DNP" "DNP")
    (property "License" "Apache-2.0")
    (property "MPN" "CR0402-FX-2200GLF")
    (property "Manufacturer" "Bourns")
    (property "Sheetfile" "interfaces.kicad_sch")
    (property "Sheetname" "Interfaces")
    (property "Tolerance" "1%")
    (property "Val" "220R")
    (property "dnp" "")
    (property "exclude_from_bom" "")
    (property "ki_description" "220R resistor in 0402 package with 1% tolerance")
    (attr exclude_from_pos_files exclude_from_bom)
    (fp_text reference "R57" (at 0.9949 0.60788 90) (layer "F.SilkS")
        (effects (font (size 0.7 0.7) (thickness 0.15)) (justify left bottom))
    )
    (fp_text value "R_220R_0402" (at 0 1.4 -90) (layer "F.Fab")
        (effects (font (size 0.7 0.7) (thickness 0.15)) (justify left bottom))
    )
    (fp_text user "${REFERENCE}" (at -0.95 3.168 -90) (layer "F.Fab") hide
        (effects (font (size 0.7 0.7) (thickness 0.15)) (justify left bottom))
    )
    (fp_text user "License: Apache-2.0" (at -0.95 5.169 -90) (layer "F.Fab") hide
        (effects (font (size 0.7 0.7) (thickness 0.15)) (justify left bottom))
    )
    (fp_text user "Author: Antmicro" (at -0.95 4.169 -90) (layer "F.Fab") hide
        (effects (font (size 0.7 0.7) (thickness 0.15)) (justify left bottom))
    )
    (fp_rect (start -0.95 -0.48) (end 0.95 0.48)
      (stroke (width 0.05) (type solid)) (fill none) (layer "F.CrtYd"))
    (fp_rect (start -0.5 -0.25) (end 0.5 0.25)
      (stroke (width 0.15) (type solid)) (fill none) (layer "F.Fab"))
    (pad "1" smd roundrect (at -0.485 0 270) (size 0.59 0.64) (layers "F.Cu" "F.Paste" "F.Mask") (roundrect_rratio 0.25)
      (net 242 "RPi_TXD") (pintype "passive"))
    (pad "2" smd roundrect (at 0.485 0 270) (size 0.59 0.64) (layers "F.Cu" "F.Paste" "F.Mask") (roundrect_rratio 0.25)
      (net 237 "Adapter_RXD") (pintype "passive"))
  )
	(footprint "scalenode-cm4-baseboard-footprints:SOT-23-3" (layer "F.Cu")
    (at 151.892 59.405 90)
    (property "Author" "Antmicro")
    (property "License" "Apache-2.0")
    (property "MPN" "BSS138-7-F")
    (property "Manufacturer" "Diodes Incorporated")
    (property "Sheetfile" "compute-module.kicad_sch")
    (property "Sheetname" "Compute module")
    (attr smd)
    (fp_text reference "Q6" (at 1.205 -2.117 180) (layer "F.SilkS")
        (effects (font (size 0.7 0.7) (thickness 0.15)) (justify left bottom))
    )
    (fp_text value "BSS138-7-F" (at -6.67 2.483 90) (layer "F.Fab")
        (effects (font (size 0.7 0.7) (thickness 0.15)) (justify left bottom))
    )
    (fp_text user "License: Apache-2.0" (at -1.8 6.8 90) (layer "F.Fab") hide
        (effects (font (size 0.7 0.7) (thickness 0.15)) (justify left bottom))
    )
    (fp_text user "Author: Antmicro" (at -1.837 5.3 90) (layer "F.Fab") hide
        (effects (font (size 0.7 0.7) (thickness 0.15)) (justify left bottom))
    )
    (fp_text user "${REFERENCE}" (at -1.837 4 90) (layer "F.Fab") hide
        (effects (font (size 0.7 0.7) (thickness 0.15)) (justify left bottom))
    )
    (fp_line (start -1.45 -1.35) (end -0.85 -1.35)
      (stroke (width 0.15) (type solid)) (layer "F.SilkS"))
    (fp_line (start -0.85 -1.35) (end -0.7 -1.5)
      (stroke (width 0.15) (type solid)) (layer "F.SilkS"))
    (fp_line (start -0.7 1.5) (end -0.7 1.35)
      (stroke (width 0.15) (type solid)) (layer "F.SilkS"))
    (fp_line (start 0.7 -1.5) (end -0.7 -1.5)
      (stroke (width 0.15) (type solid)) (layer "F.SilkS"))
    (fp_line (start 0.7 -0.4) (end 0.7 -1.5)
      (stroke (width 0.15) (type solid)) (layer "F.SilkS"))
    (fp_line (start 0.7 0.4) (end 0.7 1.5)
      (stroke (width 0.15) (type solid)) (layer "F.SilkS"))
    (fp_line (start 0.7 1.5) (end -0.7 1.5)
      (stroke (width 0.15) (type solid)) (layer "F.SilkS"))
    (fp_line (start -1.75 -0.5) (end -1.75 -1.4)
      (stroke (width 0.05) (type solid)) (layer "F.CrtYd"))
    (fp_line (start -1.75 0.5) (end -0.85 0.5)
      (stroke (width 0.05) (type solid)) (layer "F.CrtYd"))
    (fp_line (start -1.75 1.4) (end -1.75 0.5)
      (stroke (width 0.05) (type solid)) (layer "F.CrtYd"))
    (fp_line (start -0.9 -1.6) (end -0.9 -1.4)
      (stroke (width 0.05) (type solid)) (layer "F.CrtYd"))
    (fp_line (start -0.9 -1.6) (end 0.825 -1.6)
      (stroke (width 0.05) (type solid)) (layer "F.CrtYd"))
    (fp_line (start -0.9 -1.4) (end -1.75 -1.4)
      (stroke (width 0.05) (type solid)) (layer "F.CrtYd"))
    (fp_line (start -0.85 -0.5) (end -1.75 -0.5)
      (stroke (width 0.05) (type solid)) (layer "F.CrtYd"))
    (fp_line (start -0.85 0.5) (end -0.85 -0.5)
      (stroke (width 0.05) (type solid)) (layer "F.CrtYd"))
    (fp_line (start -0.85 1.4) (end -1.75 1.4)
      (stroke (width 0.05) (type solid)) (layer "F.CrtYd"))
    (fp_line (start -0.85 1.65) (end -0.85 1.4)
      (stroke (width 0.05) (type solid)) (layer "F.CrtYd"))
    (fp_line (start 0.825 -1.6) (end 0.825 -0.45)
      (stroke (width 0.05) (type solid)) (layer "F.CrtYd"))
    (fp_line (start 0.825 -0.45) (end 1.75 -0.45)
      (stroke (width 0.05) (type solid)) (layer "F.CrtYd"))
    (fp_line (start 0.85 0.45) (end 0.85 1.65)
      (stroke (width 0.05) (type solid)) (layer "F.CrtYd"))
    (fp_line (start 0.85 1.65) (end -0.85 1.65)
      (stroke (width 0.05) (type solid)) (layer "F.CrtYd"))
    (fp_line (start 1.75 -0.45) (end 1.75 0.45)
      (stroke (width 0.05) (type solid)) (layer "F.CrtYd"))
    (fp_line (start 1.75 0.45) (end 0.85 0.45)
      (stroke (width 0.05) (type solid)) (layer "F.CrtYd"))
    (fp_line (start -0.712 -1.325) (end -0.712 1.523)
      (stroke (width 0.15) (type solid)) (layer "F.Fab"))
    (fp_line (start -0.712 1.519) (end 0.688 1.519)
      (stroke (width 0.15) (type solid)) (layer "F.Fab"))
    (fp_line (start -0.437 -1.526) (end -0.712 -1.325)
      (stroke (width 0.15) (type solid)) (layer "F.Fab"))
    (fp_line (start -0.437 -1.526) (end 0.688 -1.526)
      (stroke (width 0.15) (type solid)) (layer "F.Fab"))
    (fp_line (start 0.688 1.519) (end 0.688 -1.52)
      (stroke (width 0.15) (type solid)) (layer "F.Fab"))
    (pad "1" smd roundrect (at -1.1 -0.951 90) (size 1 0.6) (layers "F.Cu" "F.Paste" "F.Mask") (roundrect_rratio 0.15)
      (net 246 "Net-(Q6-G)") (pinfunction "G") (pintype "bidirectional"))
    (pad "2" smd roundrect (at -1.1 0.949 90) (size 1 0.6) (layers "F.Cu" "F.Paste" "F.Mask") (roundrect_rratio 0.15)
      (net 11 "GND") (pinfunction "S") (pintype "bidirectional"))
    (pad "3" smd roundrect (at 1.1 -0.0005 90) (size 1 0.6) (layers "F.Cu" "F.Paste" "F.Mask") (roundrect_rratio 0.15)
      (net 243 "/Compute module/nRPi_BOOT") (pinfunction "D") (pintype "bidirectional"))
  )
	(footprint "scalenode-cm4-baseboard-footprints:R_0402_1005Metric" (layer "F.Cu")
    (at 175.808 89.377 90)
    (descr "Resistor SMD 0402")
    (tags "resistor SMD 0402")
    (property "Author" "Antmicro")
    (property "License" "Apache-2.0")
    (property "MPN" "CR0402-FX-22R0GLF")
    (property "Manufacturer" "Bourns")
    (property "Sheetfile" "interfaces.kicad_sch")
    (property "Sheetname" "Interfaces")
    (property "Tolerance" "1%")
    (property "Val" "22R")
    (property "ki_description" "22R resistor in 0402 package with 1% tolerance")
    (attr smd)
    (fp_text reference "R7" (at -0.398 -2.008 180) (layer "F.SilkS")
        (effects (font (size 0.7 0.7) (thickness 0.15)) (justify left bottom))
    )
    (fp_text value "R_22R_0402" (at 0 1.4 90) (layer "F.Fab")
        (effects (font (size 0.7 0.7) (thickness 0.15)) (justify left bottom))
    )
    (fp_text user "${REFERENCE}" (at -0.95 3.168 90) (layer "F.Fab") hide
        (effects (font (size 0.7 0.7) (thickness 0.15)) (justify left bottom))
    )
    (fp_text user "Author: Antmicro" (at -0.95 4.169 90) (layer "F.Fab") hide
        (effects (font (size 0.7 0.7) (thickness 0.15)) (justify left bottom))
    )
    (fp_text user "License: Apache-2.0" (at -0.95 5.169 90) (layer "F.Fab") hide
        (effects (font (size 0.7 0.7) (thickness 0.15)) (justify left bottom))
    )
    (fp_rect (start -0.95 -0.48) (end 0.95 0.48)
      (stroke (width 0.05) (type solid)) (fill none) (layer "F.CrtYd"))
    (fp_rect (start -0.5 -0.25) (end 0.5 0.25)
      (stroke (width 0.15) (type solid)) (fill none) (layer "F.Fab"))
    (pad "1" smd roundrect (at -0.485 0 90) (size 0.59 0.64) (layers "F.Cu" "F.Paste" "F.Mask") (roundrect_rratio 0.25)
      (net 98 "USB2_P") (pintype "passive"))
    (pad "2" smd roundrect (at 0.485 0 90) (size 0.59 0.64) (layers "F.Cu" "F.Paste" "F.Mask") (roundrect_rratio 0.25)
      (net 247 "Net-(U1-D+)") (pintype "passive"))
  )
	(footprint "scalenode-cm4-baseboard-footprints:R_0402_1005Metric" (layer "F.Cu")
    (at 176.951 89.377 90)
    (descr "Resistor SMD 0402")
    (tags "resistor SMD 0402")
    (property "Author" "Antmicro")
    (property "License" "Apache-2.0")
    (property "MPN" "CR0402-FX-22R0GLF")
    (property "Manufacturer" "Bourns")
    (property "Sheetfile" "interfaces.kicad_sch")
    (property "Sheetname" "Interfaces")
    (property "Tolerance" "1%")
    (property "Val" "22R")
    (property "ki_description" "22R resistor in 0402 package with 1% tolerance")
    (attr smd)
    (fp_text reference "R8" (at -0.373 0.499 180) (layer "F.SilkS")
        (effects (font (size 0.7 0.7) (thickness 0.15)) (justify left bottom))
    )
    (fp_text value "R_22R_0402" (at 0 1.4 90) (layer "F.Fab")
        (effects (font (size 0.7 0.7) (thickness 0.15)) (justify left bottom))
    )
    (fp_text user "Author: Antmicro" (at -0.95 4.169 90) (layer "F.Fab") hide
        (effects (font (size 0.7 0.7) (thickness 0.15)) (justify left bottom))
    )
    (fp_text user "License: Apache-2.0" (at -0.95 5.169 90) (layer "F.Fab") hide
        (effects (font (size 0.7 0.7) (thickness 0.15)) (justify left bottom))
    )
    (fp_text user "${REFERENCE}" (at -0.95 3.168 90) (layer "F.Fab") hide
        (effects (font (size 0.7 0.7) (thickness 0.15)) (justify left bottom))
    )
    (fp_rect (start -0.95 -0.48) (end 0.95 0.48)
      (stroke (width 0.05) (type solid)) (fill none) (layer "F.CrtYd"))
    (fp_rect (start -0.5 -0.25) (end 0.5 0.25)
      (stroke (width 0.15) (type solid)) (fill none) (layer "F.Fab"))
    (pad "1" smd roundrect (at -0.485 0 90) (size 0.59 0.64) (layers "F.Cu" "F.Paste" "F.Mask") (roundrect_rratio 0.25)
      (net 97 "USB2_N") (pintype "passive"))
    (pad "2" smd roundrect (at 0.485 0 90) (size 0.59 0.64) (layers "F.Cu" "F.Paste" "F.Mask") (roundrect_rratio 0.25)
      (net 248 "Net-(U1-D-)") (pintype "passive"))
  )
	(footprint "scalenode-cm4-baseboard-footprints:C_0402_1005Metric" (layer "F.Cu")
    (at 168.6438 72.4606)
    (descr "Capacitor SMD 0402")
    (tags "capacitor SMD 0402")
    (property "Author" "Antmicro")
    (property "Dielectric" "X5R")
    (property "License" "Apache-2.0")
    (property "MPN" "GRM155R61H104KE14D")
    (property "Manufacturer" "Murata")
    (property "Sheetfile" "interfaces.kicad_sch")
    (property "Sheetname" "Interfaces")
    (property "Val" "100n")
    (property "Voltage" "50V")
    (property "ki_description" " ")
    (attr smd)
    (fp_text reference "C55" (at 0.9312 0.4394) (layer "F.SilkS")
        (effects (font (size 0.7 0.7) (thickness 0.15)) (justify left bottom))
    )
    (fp_text value "C_100n_0402" (at 0 1.4) (layer "F.Fab")
        (effects (font (size 0.7 0.7) (thickness 0.15)) (justify left bottom))
    )
    (fp_text user "Author: Antmicro" (at -0.932 4.17) (layer "F.Fab") hide
        (effects (font (size 0.7 0.7) (thickness 0.15)) (justify left bottom))
    )
    (fp_text user "${REFERENCE}" (at -0.932 3.168) (layer "F.Fab") hide
        (effects (font (size 0.7 0.7) (thickness 0.15)) (justify left bottom))
    )
    (fp_text user "License: Apache-2.0" (at -0.932 5.17) (layer "F.Fab") hide
        (effects (font (size 0.7 0.7) (thickness 0.15)) (justify left bottom))
    )
    (fp_rect (start -0.94 -0.47) (end 0.94 0.47)
      (stroke (width 0.05) (type solid)) (fill none) (layer "F.CrtYd"))
    (fp_rect (start -0.499 -0.249) (end 0.499 0.249)
      (stroke (width 0.15) (type solid)) (fill none) (layer "F.Fab"))
    (pad "1" smd roundrect (at -0.484 0) (size 0.59 0.64) (layers "F.Cu" "F.Paste" "F.Mask") (roundrect_rratio 0.25)
      (net 23 "Net-(U6-3.3VOUT)") (pintype "passive"))
    (pad "2" smd roundrect (at 0.484 0) (size 0.59 0.64) (layers "F.Cu" "F.Paste" "F.Mask") (roundrect_rratio 0.25)
      (net 11 "GND") (pintype "passive"))
  )
)
